(kicad_pcb
	(version 20241229)
	(generator "pcbnew")
	(generator_version "9.0")
	(general
		(thickness 1.61)
		(legacy_teardrops no)
	)
	(paper "A3")
	(title_block
		(title "RDIMM DDR5 Tester")
		(date "2026-05-21")
		(rev "2.2.0")
		(company "Antmicro")
		(comment 9 "footprints 637-640 of 796")
	)
	(layers
		(0 "F.Cu" signal)
		(4 "In1.Cu" power)
		(6 "In2.Cu" mixed)
		(8 "In3.Cu" power)
		(10 "In4.Cu" mixed)
		(12 "In5.Cu" power)
		(14 "In6.Cu" mixed)
		(16 "In7.Cu" power)
		(18 "In8.Cu" power)
		(20 "In9.Cu" mixed)
		(22 "In10.Cu" power)
		(2 "B.Cu" signal)
		(9 "F.Adhes" user "F.Adhesive")
		(11 "B.Adhes" user "B.Adhesive")
		(13 "F.Paste" user)
		(15 "B.Paste" user)
		(5 "F.SilkS" user "F.Silkscreen")
		(7 "B.SilkS" user "B.Silkscreen")
		(1 "F.Mask" user)
		(3 "B.Mask" user)
		(17 "Dwgs.User" user "User.Drawings")
		(19 "Cmts.User" user "User.Comments")
		(21 "Eco1.User" user "User.Eco1")
		(23 "Eco2.User" user "User.Eco2")
		(25 "Edge.Cuts" user)
		(27 "Margin" user)
		(31 "F.CrtYd" user "F.Courtyard")
		(29 "B.CrtYd" user "B.Courtyard")
		(35 "F.Fab" user)
		(33 "B.Fab" user)
	)
	(footprint "antmicro-footprints:SC70-3"
		(layer "B.Cu")
		(at 112.38 166.47 180)
		(property "Reference" "Q18"
			(at -1.57 -1.23 90)
			(layer "B.SilkS")
			(effects
				(font
					(size 0.7 0.7)
					(thickness 0.15)
				)
				(justify left bottom mirror)
			)
		)
		(property "Value" "BSS138PW"
			(at 0 -2.3 0)
			(layer "B.Fab")
			(effects
				(font
					(size 0.7 0.7)
					(thickness 0.15)
				)
				(justify left bottom mirror)
			)
		)
		(property "Datasheet" "https://assets.nexperia.com/documents/data-sheet/BSS138PW.pdf"
			(at 0 0 180)
			(layer "F.Fab")
			(hide yes)
			(effects
				(font
					(size 1.27 1.27)
					(thickness 0.15)
				)
			)
		)
		(property "MPN" "BSS138PW"
			(at 0 0 180)
			(unlocked yes)
			(layer "B.Fab")
			(hide yes)
			(effects
				(font
					(size 1 1)
					(thickness 0.15)
				)
				(justify mirror)
			)
		)
		(property "Manufacturer" "Nexperia"
			(at 0 0 180)
			(unlocked yes)
			(layer "B.Fab")
			(hide yes)
			(effects
				(font
					(size 1 1)
					(thickness 0.15)
				)
				(justify mirror)
			)
		)
		(property "Author" "Antmicro"
			(at 0 0 180)
			(unlocked yes)
			(layer "B.Fab")
			(hide yes)
			(effects
				(font
					(size 1 1)
					(thickness 0.15)
				)
				(justify mirror)
			)
		)
		(property "License" "Apache-2.0"
			(at 0 0 180)
			(unlocked yes)
			(layer "B.Fab")
			(hide yes)
			(effects
				(font
					(size 1 1)
					(thickness 0.15)
				)
				(justify mirror)
			)
		)
		(sheetname "/HDMI + SD Card/")
		(sheetfile "hdmi-sd-card.kicad_sch")
		(attr smd)
		(fp_line
			(start 0.627 0.6)
			(end 0.627 0.999)
			(stroke
				(width 0.15)
				(type solid)
			)
			(layer "B.SilkS")
		)
		(fp_line
			(start 0.627 -0.6)
			(end 0.627 -1.001)
			(stroke
				(width 0.15)
				(type solid)
			)
			(layer "B.SilkS")
		)
		(fp_line
			(start -0.3 1)
			(end 0.627 0.999)
			(stroke
				(width 0.15)
				(type solid)
			)
			(layer "B.SilkS")
		)
		(fp_line
			(start -0.3 -1)
			(end 0.627 -1.001)
			(stroke
				(width 0.15)
				(type solid)
			)
			(layer "B.SilkS")
		)
		(fp_line
			(start 1.4 0.4)
			(end 1.4 -0.4)
			(stroke
				(width 0.05)
				(type solid)
			)
			(layer "B.CrtYd")
		)
		(fp_line
			(start 1.4 -0.4)
			(end 0.9 -0.4)
			(stroke
				(width 0.05)
				(type solid)
			)
			(layer "B.CrtYd")
		)
		(fp_line
			(start 0.9 1.3)
			(end 0.9 0.4)
			(stroke
				(width 0.05)
				(type solid)
			)
			(layer "B.CrtYd")
		)
		(fp_line
			(start 0.9 0.4)
			(end 1.4 0.4)
			(stroke
				(width 0.05)
				(type solid)
			)
			(layer "B.CrtYd")
		)
		(fp_line
			(start 0.9 -0.4)
			(end 0.9 -1.3)
			(stroke
				(width 0.05)
				(type solid)
			)
			(layer "B.CrtYd")
		)
		(fp_line
			(start 0.9 -1.3)
			(end -0.9 -1.3)
			(stroke
				(width 0.05)
				(type solid)
			)
			(layer "B.CrtYd")
		)
		(fp_line
			(start -0.9 1.3)
			(end 0.9 1.3)
			(stroke
				(width 0.05)
				(type solid)
			)
			(layer "B.CrtYd")
		)
		(fp_line
			(start -0.9 1.3)
			(end -0.9 1)
			(stroke
				(width 0.05)
				(type solid)
			)
			(layer "B.CrtYd")
		)
		(fp_line
			(start -0.9 1)
			(end -1.4 1)
			(stroke
				(width 0.05)
				(type solid)
			)
			(layer "B.CrtYd")
		)
		(fp_line
			(start -0.9 -1)
			(end -1.4 -1)
			(stroke
				(width 0.05)
				(type solid)
			)
			(layer "B.CrtYd")
		)
		(fp_line
			(start -0.9 -1.3)
			(end -0.9 -1)
			(stroke
				(width 0.05)
				(type solid)
			)
			(layer "B.CrtYd")
		)
		(fp_line
			(start -1.4 -1)
			(end -1.4 1)
			(stroke
				(width 0.05)
				(type solid)
			)
			(layer "B.CrtYd")
		)
		(fp_rect
			(start -0.623 0.999)
			(end 0.627 -1.001)
			(stroke
				(width 0.15)
				(type solid)
			)
			(fill no)
			(layer "B.Fab")
		)
		(fp_text user "Author: Antmicro"
			(at -1.45 -5.782 0)
			(layer "B.Fab")
			(effects
				(font
					(size 0.7 0.7)
					(thickness 0.15)
				)
				(justify left bottom mirror)
			)
		)
		(fp_text user "License: Apache-2.0"
			(at -1.45 -6.782 0)
			(layer "B.Fab")
			(effects
				(font
					(size 0.7 0.7)
					(thickness 0.15)
				)
				(justify left bottom mirror)
			)
		)
		(fp_text user "${REFERENCE}"
			(at -1.45 -4.783 0)
			(layer "B.Fab")
			(effects
				(font
					(size 0.7 0.7)
					(thickness 0.15)
				)
				(justify left bottom mirror)
			)
		)
		(pad "1" smd rect
			(at -1.051 0.65 90)
			(size 0.6 0.6)
			(layers "B.Cu" "B.Mask" "B.Paste")
			(net 506 "Net-(Q18-G)")
			(pinfunction "G")
			(pintype "passive")
		)
		(pad "2" smd rect
			(at -1.051 -0.65 90)
			(size 0.6 0.6)
			(layers "B.Cu" "B.Mask" "B.Paste")
			(net 1 "GND")
			(pinfunction "S")
			(pintype "passive")
		)
		(pad "3" smd rect
			(at 1.05 0 90)
			(size 0.6 0.6)
			(layers "B.Cu" "B.Mask" "B.Paste")
			(net 604 "/HDMI + SD Card/HDMI_IN_HPD_CONN")
			(pinfunction "D")
			(pintype "passive")
		)
	)
	(footprint "antmicro-footprints:C_0402_1005Metric"
		(layer "B.Cu")
		(at 193.622499 193.2285 90)
		(descr "Capacitor SMD 0402")
		(tags "capacitor SMD 0402")
		(property "Reference" "C251"
			(at 0.994 0.403501 90)
			(layer "B.SilkS")
			(effects
				(font
					(size 0.7 0.7)
					(thickness 0.15)
				)
				(justify right bottom mirror)
			)
		)
		(property "Value" "C_100n_0402"
			(at -1.022927 -2.155213 90)
			(layer "B.Fab")
			(effects
				(font
					(size 0.7 0.7)
					(thickness 0.15)
				)
				(justify right bottom mirror)
			)
		)
		(property "Datasheet" "https://www.murata.com/products/productdetail?partno=GRM155R61H104KE14%23"
			(at 0 0 90)
			(layer "F.Fab")
			(hide yes)
			(effects
				(font
					(size 1.27 1.27)
					(thickness 0.15)
				)
			)
		)
		(property "Manufacturer" "Murata"
			(at 0 0 90)
			(unlocked yes)
			(layer "B.Fab")
			(hide yes)
			(effects
				(font
					(size 1 1)
					(thickness 0.15)
				)
				(justify mirror)
			)
		)
		(property "MPN" "GRM155R61H104KE14D"
			(at 0 0 90)
			(unlocked yes)
			(layer "B.Fab")
			(hide yes)
			(effects
				(font
					(size 1 1)
					(thickness 0.15)
				)
				(justify mirror)
			)
		)
		(property "Val" "100n"
			(at 0 0 90)
			(unlocked yes)
			(layer "B.Fab")
			(hide yes)
			(effects
				(font
					(size 1 1)
					(thickness 0.15)
				)
				(justify mirror)
			)
		)
		(property "License" "Apache-2.0"
			(at 0 0 90)
			(unlocked yes)
			(layer "B.Fab")
			(hide yes)
			(effects
				(font
					(size 1 1)
					(thickness 0.15)
				)
				(justify mirror)
			)
		)
		(property "Author" "Antmicro"
			(at 0 0 90)
			(unlocked yes)
			(layer "B.Fab")
			(hide yes)
			(effects
				(font
					(size 1 1)
					(thickness 0.15)
				)
				(justify mirror)
			)
		)
		(property "Voltage" "50V"
			(at 0 0 90)
			(unlocked yes)
			(layer "B.Fab")
			(hide yes)
			(effects
				(font
					(size 1 1)
					(thickness 0.15)
				)
				(justify mirror)
			)
		)
		(property "Dielectric" "X5R"
			(at 0 0 90)
			(unlocked yes)
			(layer "B.Fab")
			(hide yes)
			(effects
				(font
					(size 1 1)
					(thickness 0.15)
				)
				(justify mirror)
			)
		)
		(sheetname "/FPGA MGT Interface/")
		(sheetfile "fpga-mgt.kicad_sch")
		(attr smd)
		(fp_rect
			(start -0.925 0.47)
			(end 0.925 -0.47)
			(stroke
				(width 0.05)
				(type default)
			)
			(fill no)
			(layer "B.CrtYd")
		)
		(fp_line
			(start 0.504 -0.248)
			(end -0.494 -0.248)
			(stroke
				(width 0.15)
				(type solid)
			)
			(layer "B.Fab")
		)
		(fp_line
			(start -0.494 -0.248)
			(end -0.494 0.25)
			(stroke
				(width 0.15)
				(type solid)
			)
			(layer "B.Fab")
		)
		(fp_line
			(start 0.504 0.25)
			(end 0.504 -0.248)
			(stroke
				(width 0.15)
				(type solid)
			)
			(layer "B.Fab")
		)
		(fp_line
			(start -0.494 0.25)
			(end 0.504 0.25)
			(stroke
				(width 0.15)
				(type solid)
			)
			(layer "B.Fab")
		)
		(fp_text user "${REFERENCE}"
			(at -0.939 -4.599 270)
			(layer "B.Fab")
			(effects
				(font
					(size 0.7 0.7)
					(thickness 0.15)
				)
				(justify left bottom mirror)
			)
		)
		(fp_text user "License: Apache-2.0"
			(at -0.939 -5.799 270)
			(layer "B.Fab")
			(effects
				(font
					(size 0.7 0.7)
					(thickness 0.15)
				)
				(justify left bottom mirror)
			)
		)
		(fp_text user "Author: Antmicro"
			(at -0.939 -3.399 270)
			(layer "B.Fab")
			(effects
				(font
					(size 0.7 0.7)
					(thickness 0.15)
				)
				(justify left bottom mirror)
			)
		)
		(pad "1" smd roundrect
			(at -0.48 0 90)
			(size 0.59 0.64)
			(layers "B.Cu" "B.Mask" "B.Paste")
			(roundrect_rratio 0.25)
			(net 253 "/FPGA MGT Interface/PCIE.TXD7_P")
			(pintype "passive")
		)
		(pad "2" smd roundrect
			(at 0.48 0 90)
			(size 0.59 0.64)
			(layers "B.Cu" "B.Mask" "B.Paste")
			(roundrect_rratio 0.25)
			(net 557 "/FPGA MGT Interface/GTY_224_TX0_P")
			(pintype "passive")
		)
	)
	(footprint "antmicro-footprints:C_0402_1005Metric"
		(layer "B.Cu")
		(at 185.622499 193.2285 90)
		(descr "Capacitor SMD 0402")
		(tags "capacitor SMD 0402")
		(property "Reference" "C255"
			(at 0.994 0.403501 90)
			(layer "B.SilkS")
			(effects
				(font
					(size 0.7 0.7)
					(thickness 0.15)
				)
				(justify right bottom mirror)
			)
		)
		(property "Value" "C_100n_0402"
			(at -1.022927 -2.155213 90)
			(layer "B.Fab")
			(effects
				(font
					(size 0.7 0.7)
					(thickness 0.15)
				)
				(justify right bottom mirror)
			)
		)
		(property "Datasheet" "https://www.murata.com/products/productdetail?partno=GRM155R61H104KE14%23"
			(at 0 0 90)
			(layer "F.Fab")
			(hide yes)
			(effects
				(font
					(size 1.27 1.27)
					(thickness 0.15)
				)
			)
		)
		(property "Manufacturer" "Murata"
			(at 0 0 90)
			(unlocked yes)
			(layer "B.Fab")
			(hide yes)
			(effects
				(font
					(size 1 1)
					(thickness 0.15)
				)
				(justify mirror)
			)
		)
		(property "MPN" "GRM155R61H104KE14D"
			(at 0 0 90)
			(unlocked yes)
			(layer "B.Fab")
			(hide yes)
			(effects
				(font
					(size 1 1)
					(thickness 0.15)
				)
				(justify mirror)
			)
		)
		(property "Val" "100n"
			(at 0 0 90)
			(unlocked yes)
			(layer "B.Fab")
			(hide yes)
			(effects
				(font
					(size 1 1)
					(thickness 0.15)
				)
				(justify mirror)
			)
		)
		(property "License" "Apache-2.0"
			(at 0 0 90)
			(unlocked yes)
			(layer "B.Fab")
			(hide yes)
			(effects
				(font
					(size 1 1)
					(thickness 0.15)
				)
				(justify mirror)
			)
		)
		(property "Author" "Antmicro"
			(at 0 0 90)
			(unlocked yes)
			(layer "B.Fab")
			(hide yes)
			(effects
				(font
					(size 1 1)
					(thickness 0.15)
				)
				(justify mirror)
			)
		)
		(property "Voltage" "50V"
			(at 0 0 90)
			(unlocked yes)
			(layer "B.Fab")
			(hide yes)
			(effects
				(font
					(size 1 1)
					(thickness 0.15)
				)
				(justify mirror)
			)
		)
		(property "Dielectric" "X5R"
			(at 0 0 90)
			(unlocked yes)
			(layer "B.Fab")
			(hide yes)
			(effects
				(font
					(size 1 1)
					(thickness 0.15)
				)
				(justify mirror)
			)
		)
		(sheetname "/FPGA MGT Interface/")
		(sheetfile "fpga-mgt.kicad_sch")
		(attr smd)
		(fp_rect
			(start -0.925 0.47)
			(end 0.925 -0.47)
			(stroke
				(width 0.05)
				(type default)
			)
			(fill no)
			(layer "B.CrtYd")
		)
		(fp_line
			(start 0.504 -0.248)
			(end -0.494 -0.248)
			(stroke
				(width 0.15)
				(type solid)
			)
			(layer "B.Fab")
		)
		(fp_line
			(start -0.494 -0.248)
			(end -0.494 0.25)
			(stroke
				(width 0.15)
				(type solid)
			)
			(layer "B.Fab")
		)
		(fp_line
			(start 0.504 0.25)
			(end 0.504 -0.248)
			(stroke
				(width 0.15)
				(type solid)
			)
			(layer "B.Fab")
		)
		(fp_line
			(start -0.494 0.25)
			(end 0.504 0.25)
			(stroke
				(width 0.15)
				(type solid)
			)
			(layer "B.Fab")
		)
		(fp_text user "License: Apache-2.0"
			(at -0.939 -5.799 270)
			(layer "B.Fab")
			(effects
				(font
					(size 0.7 0.7)
					(thickness 0.15)
				)
				(justify left bottom mirror)
			)
		)
		(fp_text user "${REFERENCE}"
			(at -0.939 -4.599 270)
			(layer "B.Fab")
			(effects
				(font
					(size 0.7 0.7)
					(thickness 0.15)
				)
				(justify left bottom mirror)
			)
		)
		(fp_text user "Author: Antmicro"
			(at -0.939 -3.399 270)
			(layer "B.Fab")
			(effects
				(font
					(size 0.7 0.7)
					(thickness 0.15)
				)
				(justify left bottom mirror)
			)
		)
		(pad "1" smd roundrect
			(at -0.48 0 90)
			(size 0.59 0.64)
			(layers "B.Cu" "B.Mask" "B.Paste")
			(roundrect_rratio 0.25)
			(net 257 "/FPGA MGT Interface/PCIE.TXD5_P")
			(pintype "passive")
		)
		(pad "2" smd roundrect
			(at 0.48 0 90)
			(size 0.59 0.64)
			(layers "B.Cu" "B.Mask" "B.Paste")
			(roundrect_rratio 0.25)
			(net 563 "/FPGA MGT Interface/GTY_224_TX2_P")
			(pintype "passive")
		)
	)
	(footprint "antmicro-footprints:C_0402_1005Metric_EIA"
		(layer "B.Cu")
		(at 180 159.5 -90)
		(descr "Capacitor SMD 0402 (1005 Metric), square (rectangular) end terminal, IPC_7351 nominal, (Body size source: IPC-SM-782 page 76, https://www.pcb-3d.com/wordpress/wp-content/uploads/ipc-sm-782a_amendment_1_and_2.pdf)")
		(tags "capacitor 0402")
		(property "Reference" "C310"
			(at -0.65 -1.4 90)
			(layer "B.SilkS")
			(effects
				(font
					(size 0.7 0.7)
					(thickness 0.15)
				)
				(justify left bottom mirror)
			)
		)
		(property "Value" "C_100n_0402"
			(at 0 -1.169 90)
			(layer "B.Fab")
			(effects
				(font
					(size 0.7 0.7)
					(thickness 0.15)
				)
				(justify left bottom mirror)
			)
		)
		(property "Datasheet" "https://www.murata.com/products/productdetail?partno=GRM155R61H104KE14%23"
			(at 0 0 270)
			(layer "F.Fab")
			(hide yes)
			(effects
				(font
					(size 1.27 1.27)
					(thickness 0.15)
				)
			)
		)
		(property "MPN" "GRM155R61H104KE14D"
			(at 0 0 270)
			(unlocked yes)
			(layer "B.Fab")
			(hide yes)
			(effects
				(font
					(size 1 1)
					(thickness 0.15)
				)
				(justify mirror)
			)
		)
		(property "Manufacturer" "Murata"
			(at 0 0 270)
			(unlocked yes)
			(layer "B.Fab")
			(hide yes)
			(effects
				(font
					(size 1 1)
					(thickness 0.15)
				)
				(justify mirror)
			)
		)
		(property "License" "Apache-2.0"
			(at 0 0 270)
			(unlocked yes)
			(layer "B.Fab")
			(hide yes)
			(effects
				(font
					(size 1 1)
					(thickness 0.15)
				)
				(justify mirror)
			)
		)
		(property "Author" "Antmicro"
			(at 0 0 270)
			(unlocked yes)
			(layer "B.Fab")
			(hide yes)
			(effects
				(font
					(size 1 1)
					(thickness 0.15)
				)
				(justify mirror)
			)
		)
		(property "Val" "100n"
			(at 0 0 270)
			(unlocked yes)
			(layer "B.Fab")
			(hide yes)
			(effects
				(font
					(size 1 1)
					(thickness 0.15)
				)
				(justify mirror)
			)
		)
		(property "Voltage" "50V"
			(at 0 0 270)
			(unlocked yes)
			(layer "B.Fab")
			(hide yes)
			(effects
				(font
					(size 1 1)
					(thickness 0.15)
				)
				(justify mirror)
			)
		)
		(property "Dielectric" "X5R"
			(at 0 0 270)
			(unlocked yes)
			(layer "B.Fab")
			(hide yes)
			(effects
				(font
					(size 1 1)
					(thickness 0.15)
				)
				(justify mirror)
			)
		)
		(sheetname "/FPGA power/")
		(sheetfile "fpga-power.kicad_sch")
		(attr smd)
		(fp_rect
			(start -0.95 0.45)
			(end 0.95 -0.45)
			(stroke
				(width 0.05)
				(type default)
			)
			(fill no)
			(layer "B.CrtYd")
		)
		(fp_line
			(start -0.5 0.25)
			(end 0.498 0.25)
			(stroke
				(width 0.15)
				(type solid)
			)
			(layer "B.Fab")
		)
		(fp_line
			(start 0.498 0.25)
			(end 0.498 -0.248)
			(stroke
				(width 0.15)
				(type solid)
			)
			(layer "B.Fab")
		)
		(fp_line
			(start -0.5 -0.248)
			(end -0.5 0.25)
			(stroke
				(width 0.15)
				(type solid)
			)
			(layer "B.Fab")
		)
		(fp_line
			(start 0.498 -0.248)
			(end -0.5 -0.248)
			(stroke
				(width 0.15)
				(type solid)
			)
			(layer "B.Fab")
		)
		(fp_text user "${REFERENCE}"
			(at -0.9656 -3.169 90)
			(layer "B.Fab")
			(effects
				(font
					(size 0.7 0.7)
					(thickness 0.15)
				)
				(justify left bottom mirror)
			)
		)
		(fp_text user "License: Apache-2.0"
			(at -0.9656 -4.369 90)
			(layer "B.Fab")
			(effects
				(font
					(size 0.7 0.7)
					(thickness 0.15)
				)
				(justify left bottom mirror)
			)
		)
		(fp_text user "Author: Antmicro"
			(at -0.9656 -5.569 90)
			(layer "B.Fab")
			(effects
				(font
					(size 0.7 0.7)
					(thickness 0.15)
				)
				(justify left bottom mirror)
			)
		)
		(pad "1" smd roundrect
			(at -0.5 0 180)
			(size 0.6 0.6)
			(layers "B.Cu" "B.Mask" "B.Paste")
			(roundrect_rratio 0.25)
			(net 1 "GND")
			(pintype "passive")
		)
		(pad "2" smd roundrect
			(at 0.498 0 270)
			(size 0.6 0.6)
			(layers "B.Cu" "B.Mask" "B.Paste")
			(roundrect_rratio 0.25)
			(net 172 "+1V2_MGTAVTT")
			(pintype "passive")
		)
	)
)
